(kicad_pcb
	(version 20260206)
	(generator "pcbnew")
	(generator_version "10.0")
	(general
		(thickness 1.6)
		(legacy_teardrops no)
	)
	(paper "A4")
	(title_block
		(title "Bryce Canyon_IOM_M2_16342-2_OCP.brd")
		(comment 1 "Bryce Canyon / footprints 933-940 of 1146")
	)
	(layers
		(0 "F.Cu" signal "TOP")
		(4 "In1.Cu" signal "L2GND")
		(6 "In2.Cu" signal "L3")
		(8 "In3.Cu" signal "L4VCC")
		(10 "In4.Cu" signal "L5VCC")
		(12 "In5.Cu" signal "L6")
		(14 "In6.Cu" signal "L7GND")
		(2 "B.Cu" signal "BOTTOM")
		(9 "F.Adhes" user "F.Adhesive")
		(11 "B.Adhes" user "B.Adhesive")
		(13 "F.Paste" user "Package Geometry/Pastemask Top")
		(15 "B.Paste" user "Package Geometry/Pastemask Bottom")
		(5 "F.SilkS" user "Ref Des/Silkscreen Top")
		(7 "B.SilkS" user "Ref Des/Silkscreen Bottom")
		(1 "F.Mask" user "Board Geometry/Soldermask Top")
		(3 "B.Mask" user "Board Geometry/Soldermask Bottom")
		(17 "Dwgs.User" user "User.Drawings")
		(19 "Cmts.User" user "User.Comments")
		(21 "Eco1.User" user "User.Eco1")
		(23 "Eco2.User" user "User.Eco2")
		(25 "Edge.Cuts" user "Board Geometry/Outline")
		(27 "Margin" user)
		(31 "F.CrtYd" user "Package Geometry/Place Bound Top")
		(29 "B.CrtYd" user "Package Geometry/Place Bound Bottom")
		(35 "F.Fab" user "Ref Des/Assembly Top")
		(33 "B.Fab" user "Ref Des/Assembly Bottom")
	)
	(footprint ""
		(layer "B.Cu")
		(at 95.4024 -152.7556 180)
		(property "Reference" "C13"
			(at 0 0 0)
			(layer "B.SilkS")
			(hide yes)
			(effects
				(font
					(size 1.27 1.27)
				)
				(justify mirror)
			)
		)
		(property "Value" "SC1U16V3KX-5GP"
			(at 0 -2.8194 180)
			(unlocked yes)
			(layer "B.Fab")
			(hide yes)
			(effects
				(font
					(size 1.016 1.016)
					(thickness 0.1524)
				)
				(justify mirror)
			)
		)
		(property "Device Type" "C603H36"
			(at 0 -4.3434 180)
			(unlocked yes)
			(layer "B.Fab")
			(hide yes)
			(effects
				(font
					(size 1.016 1.016)
					(thickness 0.1524)
				)
				(justify mirror)
			)
		)
		(duplicate_pad_numbers_are_jumpers no)
		(fp_line
			(start -0.508 0)
			(end 0.508 0)
			(stroke
				(width 0.2032)
				(type default)
			)
			(layer "B.SilkS")
		)
		(fp_rect
			(start 0.5842 1.3335)
			(end -0.5842 -1.3335)
			(stroke
				(width 0)
				(type default)
			)
			(fill no)
			(layer "B.CrtYd")
		)
		(fp_rect
			(start 0.5842 1.3335)
			(end -0.5842 -1.3335)
			(stroke
				(width 0)
				(type default)
			)
			(fill no)
			(layer "B.Fab")
		)
		(pad "1" smd custom
			(at 0 -0.762)
			(size 0.2159 0.2159)
			(layers "B.Cu" "B.Mask" "B.Paste")
			(net "P3V3_STBY")
			(options
				(clearance outline)
				(anchor circle)
			)
			(primitives
				(gr_poly
					(pts
						(arc
							(start -0.3302 0.4318)
							(mid -0.402042 0.402042)
							(end -0.4318 0.3302)
						)
						(arc
							(start -0.4318 -0.3302)
							(mid -0.402042 -0.402042)
							(end -0.3302 -0.4318)
						)
						(arc
							(start 0.3302 -0.4318)
							(mid 0.402042 -0.402042)
							(end 0.4318 -0.3302)
						)
						(arc
							(start 0.4318 0.3302)
							(mid 0.402042 0.402042)
							(end 0.3302 0.4318)
						)
					)
					(width 0)
					(fill yes)
				)
			)
		)
		(pad "2" smd custom
			(at 0 0.762)
			(size 0.2159 0.2159)
			(layers "B.Cu" "B.Mask" "B.Paste")
			(net "GND")
			(options
				(clearance outline)
				(anchor circle)
			)
			(primitives
				(gr_poly
					(pts
						(arc
							(start -0.3302 0.4318)
							(mid -0.402042 0.402042)
							(end -0.4318 0.3302)
						)
						(arc
							(start -0.4318 -0.3302)
							(mid -0.402042 -0.402042)
							(end -0.3302 -0.4318)
						)
						(arc
							(start 0.3302 -0.4318)
							(mid 0.402042 -0.402042)
							(end 0.4318 -0.3302)
						)
						(arc
							(start 0.4318 0.3302)
							(mid 0.402042 0.402042)
							(end 0.3302 0.4318)
						)
					)
					(width 0)
					(fill yes)
				)
			)
		)
	)
	(footprint ""
		(layer "B.Cu")
		(at 52.832 -132.08)
		(property "Reference" "C109"
			(at 0 0 0)
			(layer "B.SilkS")
			(hide yes)
			(effects
				(font
					(size 1.27 1.27)
				)
				(justify mirror)
			)
		)
		(property "Value" "SC1U16V3KX-5GP"
			(at 0 -2.8194 0)
			(unlocked yes)
			(layer "B.Fab")
			(hide yes)
			(effects
				(font
					(size 1.016 1.016)
					(thickness 0.1524)
				)
				(justify mirror)
			)
		)
		(property "Device Type" "C603H36"
			(at 0 -4.3434 0)
			(unlocked yes)
			(layer "B.Fab")
			(hide yes)
			(effects
				(font
					(size 1.016 1.016)
					(thickness 0.1524)
				)
				(justify mirror)
			)
		)
		(duplicate_pad_numbers_are_jumpers no)
		(fp_line
			(start -0.508 0)
			(end 0.508 0)
			(stroke
				(width 0.2032)
				(type default)
			)
			(layer "B.SilkS")
		)
		(fp_rect
			(start 0.5842 1.3335)
			(end -0.5842 -1.3335)
			(stroke
				(width 0)
				(type default)
			)
			(fill no)
			(layer "B.CrtYd")
		)
		(fp_rect
			(start 0.5842 1.3335)
			(end -0.5842 -1.3335)
			(stroke
				(width 0)
				(type default)
			)
			(fill no)
			(layer "B.Fab")
		)
		(pad "1" smd custom
			(at 0 -0.762 180)
			(size 0.2159 0.2159)
			(layers "B.Cu" "B.Mask" "B.Paste")
			(net "P1V15_STBY")
			(options
				(clearance outline)
				(anchor circle)
			)
			(primitives
				(gr_poly
					(pts
						(arc
							(start -0.3302 0.4318)
							(mid -0.402042 0.402042)
							(end -0.4318 0.3302)
						)
						(arc
							(start -0.4318 -0.3302)
							(mid -0.402042 -0.402042)
							(end -0.3302 -0.4318)
						)
						(arc
							(start 0.3302 -0.4318)
							(mid 0.402042 -0.402042)
							(end 0.4318 -0.3302)
						)
						(arc
							(start 0.4318 0.3302)
							(mid 0.402042 0.402042)
							(end 0.3302 0.4318)
						)
					)
					(width 0)
					(fill yes)
				)
			)
		)
		(pad "2" smd custom
			(at 0 0.762 180)
			(size 0.2159 0.2159)
			(layers "B.Cu" "B.Mask" "B.Paste")
			(net "GND")
			(options
				(clearance outline)
				(anchor circle)
			)
			(primitives
				(gr_poly
					(pts
						(arc
							(start -0.3302 0.4318)
							(mid -0.402042 0.402042)
							(end -0.4318 0.3302)
						)
						(arc
							(start -0.4318 -0.3302)
							(mid -0.402042 -0.402042)
							(end -0.3302 -0.4318)
						)
						(arc
							(start 0.3302 -0.4318)
							(mid 0.402042 -0.402042)
							(end 0.4318 -0.3302)
						)
						(arc
							(start 0.4318 0.3302)
							(mid 0.402042 0.402042)
							(end 0.3302 0.4318)
						)
					)
					(width 0)
					(fill yes)
				)
			)
		)
	)
	(footprint ""
		(layer "B.Cu")
		(at 81.744566 -46.659292 -90)
		(property "Reference" "C511"
			(at 0 0 90)
			(layer "B.SilkS")
			(hide yes)
			(effects
				(font
					(size 1.27 1.27)
				)
				(justify mirror)
			)
		)
		(property "Value" "SC10U16V5KX-7-GP-U"
			(at 0.0762 -6.1214 270)
			(unlocked yes)
			(layer "B.Fab")
			(hide yes)
			(effects
				(font
					(size 1.016 1.016)
					(thickness 0.1524)
				)
				(justify mirror)
			)
		)
		(property "Device Type" "C805H58"
			(at 0.0762 -8.1534 270)
			(unlocked yes)
			(layer "B.Fab")
			(hide yes)
			(effects
				(font
					(size 1.016 1.016)
					(thickness 0.1524)
				)
				(justify mirror)
			)
		)
		(duplicate_pad_numbers_are_jumpers no)
		(fp_line
			(start -0.635 0)
			(end 0.635 0)
			(stroke
				(width 0.508)
				(type default)
			)
			(layer "B.SilkS")
		)
		(fp_rect
			(start 0.9652 1.778)
			(end -0.9652 -1.778)
			(stroke
				(width 0)
				(type default)
			)
			(fill no)
			(layer "B.CrtYd")
		)
		(fp_poly
			(pts
				(xy 0.9652 -1.778) (xy -0.9652 -1.778) (xy -0.9652 1.778) (xy 0.9652 1.778)
			)
			(stroke
				(width 0)
				(type default)
			)
			(fill no)
			(layer "B.Fab")
		)
		(pad "1" smd rect
			(at 0 -0.9652 90)
			(size 1.397 1.143)
			(layers "B.Cu" "B.Mask" "B.Paste")
			(net "P5V_STBY")
		)
		(pad "2" smd rect
			(at 0 0.9652 90)
			(size 1.397 1.143)
			(layers "B.Cu" "B.Mask" "B.Paste")
			(net "GND")
		)
	)
	(footprint ""
		(layer "B.Cu")
		(at 63.5762 -160.4772)
		(property "Reference" "C88"
			(at 0 0 0)
			(layer "B.SilkS")
			(hide yes)
			(effects
				(font
					(size 1.27 1.27)
				)
				(justify mirror)
			)
		)
		(property "Value" "SC100P50V2JN-3GP"
			(at -1.1811 -2.7051 0)
			(unlocked yes)
			(layer "B.Fab")
			(hide yes)
			(effects
				(font
					(size 1.016 1.016)
					(thickness 0.1524)
				)
				(justify mirror)
			)
		)
		(property "Device Type" "C402H22"
			(at -1.1811 -4.2291 0)
			(unlocked yes)
			(layer "B.Fab")
			(hide yes)
			(effects
				(font
					(size 1.016 1.016)
					(thickness 0.1524)
				)
				(justify mirror)
			)
		)
		(duplicate_pad_numbers_are_jumpers no)
		(fp_rect
			(start 0.4318 0.9525)
			(end -0.4318 -0.9525)
			(stroke
				(width 0)
				(type default)
			)
			(fill no)
			(layer "B.CrtYd")
		)
		(fp_rect
			(start 0.4318 0.9525)
			(end -0.4318 -0.9525)
			(stroke
				(width 0)
				(type default)
			)
			(fill no)
			(layer "B.Fab")
		)
		(pad "1" smd custom
			(at 0 -0.4445 180)
			(size 0.1524 0.1524)
			(layers "B.Cu" "B.Mask" "B.Paste")
			(net "ADCAV33")
			(options
				(clearance outline)
				(anchor circle)
			)
			(primitives
				(gr_poly
					(pts
						(arc
							(start 0.3048 0.2032)
							(mid 0.275042 0.275042)
							(end 0.2032 0.3048)
						)
						(arc
							(start -0.2032 0.3048)
							(mid -0.275042 0.275042)
							(end -0.3048 0.2032)
						)
						(arc
							(start -0.3048 -0.2032)
							(mid -0.275042 -0.275042)
							(end -0.2032 -0.3048)
						)
						(arc
							(start 0.2032 -0.3048)
							(mid 0.275042 -0.275042)
							(end 0.3048 -0.2032)
						)
					)
					(width 0)
					(fill yes)
				)
			)
		)
		(pad "2" smd custom
			(at 0 0.4445 180)
			(size 0.1524 0.1524)
			(layers "B.Cu" "B.Mask" "B.Paste")
			(net "GND")
			(options
				(clearance outline)
				(anchor circle)
			)
			(primitives
				(gr_poly
					(pts
						(arc
							(start 0.3048 0.2032)
							(mid 0.275042 0.275042)
							(end 0.2032 0.3048)
						)
						(arc
							(start -0.2032 0.3048)
							(mid -0.275042 0.275042)
							(end -0.3048 0.2032)
						)
						(arc
							(start -0.3048 -0.2032)
							(mid -0.275042 -0.275042)
							(end -0.2032 -0.3048)
						)
						(arc
							(start 0.2032 -0.3048)
							(mid 0.275042 -0.275042)
							(end 0.3048 -0.2032)
						)
					)
					(width 0)
					(fill yes)
				)
			)
		)
	)
	(footprint ""
		(layer "B.Cu")
		(at 90.84437 -172.57903 180)
		(property "Reference" "R417"
			(at 0 0 0)
			(layer "B.SilkS")
			(hide yes)
			(effects
				(font
					(size 1.27 1.27)
				)
				(justify mirror)
			)
		)
		(property "Value" "0R2J-2-GP"
			(at -0.064008 -3.993896 180)
			(unlocked yes)
			(layer "B.Fab")
			(hide yes)
			(effects
				(font
					(size 1.016 1.016)
					(thickness 0.1524)
				)
				(justify mirror)
			)
		)
		(property "Device Type" "R402H16"
			(at -0.064008 -5.517896 180)
			(unlocked yes)
			(layer "B.Fab")
			(hide yes)
			(effects
				(font
					(size 1.016 1.016)
					(thickness 0.1524)
				)
				(justify mirror)
			)
		)
		(duplicate_pad_numbers_are_jumpers no)
		(fp_line
			(start 0.508 -0.9398)
			(end 0.508 0.9398)
			(stroke
				(width 0.1524)
				(type default)
			)
			(layer "B.SilkS")
		)
		(fp_line
			(start -0.508 -0.9398)
			(end 0.508 -0.9398)
			(stroke
				(width 0.1524)
				(type default)
			)
			(layer "B.SilkS")
		)
		(fp_rect
			(start 0.508 0.9398)
			(end -0.508 -0.9398)
			(stroke
				(width 0)
				(type default)
			)
			(fill no)
			(layer "B.CrtYd")
		)
		(fp_rect
			(start 0.508 0.9398)
			(end -0.508 -0.9398)
			(stroke
				(width 0)
				(type default)
			)
			(fill no)
			(layer "B.Fab")
		)
		(pad "1" smd custom
			(at 0 -0.4445)
			(size 0.1397 0.1397)
			(layers "B.Cu" "B.Mask" "B.Paste")
			(net "PCIE_RST_R_N")
			(options
				(clearance outline)
				(anchor circle)
			)
			(primitives
				(gr_poly
					(pts
						(arc
							(start -0.1778 0.2794)
							(mid -0.249642 0.249642)
							(end -0.2794 0.1778)
						)
						(arc
							(start -0.2794 -0.1778)
							(mid -0.249642 -0.249642)
							(end -0.1778 -0.2794)
						)
						(arc
							(start 0.1778 -0.2794)
							(mid 0.249642 -0.249642)
							(end 0.2794 -0.1778)
						)
						(arc
							(start 0.2794 0.1778)
							(mid 0.249642 0.249642)
							(end 0.1778 0.2794)
						)
					)
					(width 0)
					(fill yes)
				)
			)
		)
		(pad "2" smd custom
			(at 0 0.4445)
			(size 0.1397 0.1397)
			(layers "B.Cu" "B.Mask" "B.Paste")
			(net "PCIE_COMP_TO_IOM_RST_4")
			(options
				(clearance outline)
				(anchor circle)
			)
			(primitives
				(gr_poly
					(pts
						(arc
							(start -0.1778 0.2794)
							(mid -0.249642 0.249642)
							(end -0.2794 0.1778)
						)
						(arc
							(start -0.2794 -0.1778)
							(mid -0.249642 -0.249642)
							(end -0.1778 -0.2794)
						)
						(arc
							(start 0.1778 -0.2794)
							(mid 0.249642 -0.249642)
							(end 0.2794 -0.1778)
						)
						(arc
							(start 0.2794 0.1778)
							(mid 0.249642 0.249642)
							(end 0.1778 0.2794)
						)
					)
					(width 0)
					(fill yes)
				)
			)
		)
	)
	(footprint ""
		(layer "B.Cu")
		(at 54.2036 -163.1188 -90)
		(property "Reference" "R401"
			(at 0 0 90)
			(layer "B.SilkS")
			(hide yes)
			(effects
				(font
					(size 1.27 1.27)
				)
				(justify mirror)
			)
		)
		(property "Value" "7K87R2F-GP"
			(at -0.064008 -3.993896 270)
			(unlocked yes)
			(layer "B.Fab")
			(hide yes)
			(effects
				(font
					(size 1.016 1.016)
					(thickness 0.1524)
				)
				(justify mirror)
			)
		)
		(property "Device Type" "R402H16"
			(at -0.064008 -5.517896 270)
			(unlocked yes)
			(layer "B.Fab")
			(hide yes)
			(effects
				(font
					(size 1.016 1.016)
					(thickness 0.1524)
				)
				(justify mirror)
			)
		)
		(duplicate_pad_numbers_are_jumpers no)
		(fp_line
			(start -0.508 -0.9398)
			(end 0.508 -0.9398)
			(stroke
				(width 0.1524)
				(type default)
			)
			(layer "B.SilkS")
		)
		(fp_line
			(start 0.508 -0.9398)
			(end 0.508 0.9398)
			(stroke
				(width 0.1524)
				(type default)
			)
			(layer "B.SilkS")
		)
		(fp_rect
			(start 0.508 0.9398)
			(end -0.508 -0.9398)
			(stroke
				(width 0)
				(type default)
			)
			(fill no)
			(layer "B.CrtYd")
		)
		(fp_rect
			(start 0.508 0.9398)
			(end -0.508 -0.9398)
			(stroke
				(width 0)
				(type default)
			)
			(fill no)
			(layer "B.Fab")
		)
		(pad "1" smd custom
			(at 0 -0.4445 90)
			(size 0.1397 0.1397)
			(layers "B.Cu" "B.Mask" "B.Paste")
			(net "P12V_STBY")
			(options
				(clearance outline)
				(anchor circle)
			)
			(primitives
				(gr_poly
					(pts
						(arc
							(start -0.1778 0.2794)
							(mid -0.249642 0.249642)
							(end -0.2794 0.1778)
						)
						(arc
							(start -0.2794 -0.1778)
							(mid -0.249642 -0.249642)
							(end -0.1778 -0.2794)
						)
						(arc
							(start 0.1778 -0.2794)
							(mid 0.249642 -0.249642)
							(end 0.2794 -0.1778)
						)
						(arc
							(start 0.2794 0.1778)
							(mid 0.249642 0.249642)
							(end 0.1778 0.2794)
						)
					)
					(width 0)
					(fill yes)
				)
			)
		)
		(pad "2" smd custom
			(at 0 0.4445 90)
			(size 0.1397 0.1397)
			(layers "B.Cu" "B.Mask" "B.Paste")
			(net "ADC_12V")
			(options
				(clearance outline)
				(anchor circle)
			)
			(primitives
				(gr_poly
					(pts
						(arc
							(start -0.1778 0.2794)
							(mid -0.249642 0.249642)
							(end -0.2794 0.1778)
						)
						(arc
							(start -0.2794 -0.1778)
							(mid -0.249642 -0.249642)
							(end -0.1778 -0.2794)
						)
						(arc
							(start 0.1778 -0.2794)
							(mid 0.249642 -0.249642)
							(end 0.2794 -0.1778)
						)
						(arc
							(start 0.2794 0.1778)
							(mid 0.249642 0.249642)
							(end 0.1778 0.2794)
						)
					)
					(width 0)
					(fill yes)
				)
			)
		)
	)
	(footprint ""
		(layer "B.Cu")
		(at 16.319754 -129.076958 180)
		(property "Reference" "R258"
			(at 0 0 0)
			(layer "B.SilkS")
			(hide yes)
			(effects
				(font
					(size 1.27 1.27)
				)
				(justify mirror)
			)
		)
		(property "Value" "120R2F-GP"
			(at -0.064008 -3.993896 180)
			(unlocked yes)
			(layer "B.Fab")
			(hide yes)
			(effects
				(font
					(size 1.016 1.016)
					(thickness 0.1524)
				)
				(justify mirror)
			)
		)
		(property "Device Type" "R402H16"
			(at -0.064008 -5.517896 180)
			(unlocked yes)
			(layer "B.Fab")
			(hide yes)
			(effects
				(font
					(size 1.016 1.016)
					(thickness 0.1524)
				)
				(justify mirror)
			)
		)
		(duplicate_pad_numbers_are_jumpers no)
		(fp_line
			(start 0.508 -0.9398)
			(end 0.508 0.9398)
			(stroke
				(width 0.1524)
				(type default)
			)
			(layer "B.SilkS")
		)
		(fp_line
			(start -0.508 -0.9398)
			(end 0.508 -0.9398)
			(stroke
				(width 0.1524)
				(type default)
			)
			(layer "B.SilkS")
		)
		(fp_rect
			(start 0.508 0.9398)
			(end -0.508 -0.9398)
			(stroke
				(width 0)
				(type default)
			)
			(fill no)
			(layer "B.CrtYd")
		)
		(fp_rect
			(start 0.508 0.9398)
			(end -0.508 -0.9398)
			(stroke
				(width 0)
				(type default)
			)
			(fill no)
			(layer "B.Fab")
		)
		(pad "1" smd custom
			(at 0 -0.4445)
			(size 0.1397 0.1397)
			(layers "B.Cu" "B.Mask" "B.Paste")
			(net "GND")
			(options
				(clearance outline)
				(anchor circle)
			)
			(primitives
				(gr_poly
					(pts
						(arc
							(start -0.1778 0.2794)
							(mid -0.249642 0.249642)
							(end -0.2794 0.1778)
						)
						(arc
							(start -0.2794 -0.1778)
							(mid -0.249642 -0.249642)
							(end -0.1778 -0.2794)
						)
						(arc
							(start 0.1778 -0.2794)
							(mid 0.249642 -0.249642)
							(end 0.2794 -0.1778)
						)
						(arc
							(start 0.2794 0.1778)
							(mid 0.249642 0.249642)
							(end 0.1778 0.2794)
						)
					)
					(width 0)
					(fill yes)
				)
			)
		)
		(pad "2" smd custom
			(at 0 0.4445)
			(size 0.1397 0.1397)
			(layers "B.Cu" "B.Mask" "B.Paste")
			(net "MEMA_12")
			(options
				(clearance outline)
				(anchor circle)
			)
			(primitives
				(gr_poly
					(pts
						(arc
							(start -0.1778 0.2794)
							(mid -0.249642 0.249642)
							(end -0.2794 0.1778)
						)
						(arc
							(start -0.2794 -0.1778)
							(mid -0.249642 -0.249642)
							(end -0.1778 -0.2794)
						)
						(arc
							(start 0.1778 -0.2794)
							(mid 0.249642 -0.249642)
							(end 0.2794 -0.1778)
						)
						(arc
							(start 0.2794 0.1778)
							(mid 0.249642 0.249642)
							(end 0.1778 0.2794)
						)
					)
					(width 0)
					(fill yes)
				)
			)
		)
	)
	(footprint ""
		(layer "B.Cu")
		(at 174.369984 -130.720338 180)
		(property "Reference" "C615"
			(at 0 0 0)
			(layer "B.SilkS")
			(hide yes)
			(effects
				(font
					(size 1.27 1.27)
				)
				(justify mirror)
			)
		)
		(property "Value" "SCD1U16V2KX-3GP"
			(at -1.1811 -2.7051 180)
			(unlocked yes)
			(layer "B.Fab")
			(hide yes)
			(effects
				(font
					(size 1.016 1.016)
					(thickness 0.1524)
				)
				(justify mirror)
			)
		)
		(property "Device Type" "C402H22"
			(at -1.1811 -4.2291 180)
			(unlocked yes)
			(layer "B.Fab")
			(hide yes)
			(effects
				(font
					(size 1.016 1.016)
					(thickness 0.1524)
				)
				(justify mirror)
			)
		)
		(duplicate_pad_numbers_are_jumpers no)
		(fp_rect
			(start 0.4318 0.9525)
			(end -0.4318 -0.9525)
			(stroke
				(width 0)
				(type default)
			)
			(fill no)
			(layer "B.CrtYd")
		)
		(fp_rect
			(start 0.4318 0.9525)
			(end -0.4318 -0.9525)
			(stroke
				(width 0)
				(type default)
			)
			(fill no)
			(layer "B.Fab")
		)
		(pad "1" smd custom
			(at 0 -0.4445)
			(size 0.1524 0.1524)
			(layers "B.Cu" "B.Mask" "B.Paste")
			(net "P3V3_M2")
			(options
				(clearance outline)
				(anchor circle)
			)
			(primitives
				(gr_poly
					(pts
						(arc
							(start 0.3048 0.2032)
							(mid 0.275042 0.275042)
							(end 0.2032 0.3048)
						)
						(arc
							(start -0.2032 0.3048)
							(mid -0.275042 0.275042)
							(end -0.3048 0.2032)
						)
						(arc
							(start -0.3048 -0.2032)
							(mid -0.275042 -0.275042)
							(end -0.2032 -0.3048)
						)
						(arc
							(start 0.2032 -0.3048)
							(mid 0.275042 -0.275042)
							(end 0.3048 -0.2032)
						)
					)
					(width 0)
					(fill yes)
				)
			)
		)
		(pad "2" smd custom
			(at 0 0.4445)
			(size 0.1524 0.1524)
			(layers "B.Cu" "B.Mask" "B.Paste")
			(net "GND")
			(options
				(clearance outline)
				(anchor circle)
			)
			(primitives
				(gr_poly
					(pts
						(arc
							(start 0.3048 0.2032)
							(mid 0.275042 0.275042)
							(end 0.2032 0.3048)
						)
						(arc
							(start -0.2032 0.3048)
							(mid -0.275042 0.275042)
							(end -0.3048 0.2032)
						)
						(arc
							(start -0.3048 -0.2032)
							(mid -0.275042 -0.275042)
							(end -0.2032 -0.3048)
						)
						(arc
							(start 0.2032 -0.3048)
							(mid 0.275042 -0.275042)
							(end 0.3048 -0.2032)
						)
					)
					(width 0)
					(fill yes)
				)
			)
		)
	)
)
